FILE_TYPE = MULTI_PHYS_TABLE;

PART 'PI3CSW12ZUAEX'

{========================================================================================}
:VALUE           | PART_TYPE | MATERIAL | PART_NUMBER    = STANDARD    | LIFECYCLE     | PART_NUMBER   | JEDEC_TYPE         | DESCRIPTION                          | MANUFTR | MANUF_PN        | RD_CMPLS_LVL | CMPLS_LVL | FROM_PJ       | CLASS | DIP_SMD | DATA                    | EE_CHECK_LIST | FP_ECN | PSL | CREATOR | STATUS | MSD | ESD_CDM | ESD_HBM | ESD_MM | PIN_LENGTH_SHORT_PIN | PIN_LENGTH_LONG_PIN | CREATEDAY  ;
{========================================================================================}
 'PI3CSW12ZUAEX' | 'SMLF'    | 'IC'     | 'AL3CSW12000'(!) = ''          | ''            | 'AL3CSW12000' |'UQFN10_0-5_2X1-5'| 'IC(10P)PI3CSW12ZUAEX(UQFN)'         | 'DDS'   | 'PI3CSW12ZUAEX' | 'EP(V1)'     | ''        | 'S6Z-TOM'     | 'IC'  | ''      | 'DDS_PI3CSW12ZUAEX.pdf' | ''            | ''     | ''  | ''      | ''     | ''  | ''      | ''      | ''     | '0 MILS'             | '0 MILS'            | '20210331'
 'PI3CSW12ZUAEX' | 'SMLF'    | 'EMPTY'  | 'AL3CSW12000'(!) = ''          | ''            | 'AL3CSW12000' |'UQFN10_0-5_2X1-5'| 'IC(10P)PI3CSW12ZUAEX(UQFN)'         | 'DDS'   | 'PI3CSW12ZUAEX' | 'EP(V1)'     | ''        | 'S6Z-TOM'     | 'IC'  | ''      | 'DDS_PI3CSW12ZUAEX.pdf' | ''            | ''     | ''  | ''      | ''     | ''  | ''      | ''      | ''     | '0 MILS'             | '0 MILS'            | '20210331'
 'PI3CSW12ZUAEX' | 'SMLF'    | 'IC'     | 'AL3CSW12001'(!) = ''               | ''               | 'AL3CSW12001' |'UQFN10_0-5_2X1-5'| 'IC(10P) PI3CSW12ZUAEX (UQFN)AMAASN' | 'DDS'   | 'PI3CSW12ZUAEX' | 'EP(V1)'     | 'EP(V1)'  | 'A5G-JASMINE' | 'IC'  | ''      | 'DDS_PI3CSW12ZUAEX.pdf' | ''            | ''     | ''  | ''      | ''     | ''  | ''      | ''      | ''     | '0 MILS'             | '0 MILS'            | '20230502'
 'PI3CSW12ZUAEX' | 'SMLF'    | 'EMPTY'  | 'AL3CSW12001'(!) = ''               | ''               | 'AL3CSW12001' |'UQFN10_0-5_2X1-5'| 'IC(10P) PI3CSW12ZUAEX (UQFN)AMAASN' | 'DDS'   | 'PI3CSW12ZUAEX' | 'EP(V1)'     | 'EP(V1)'  | 'A5G-JASMINE' | 'IC'  | ''      | 'DDS_PI3CSW12ZUAEX.pdf' | ''            | ''     | ''  | ''      | ''     | ''  | ''      | ''      | ''     | '0 MILS'             | '0 MILS'            | '20230502'

END_PART

END.

